(kicad_pcb
	(version 20260206)
	(generator "pcbnew")
	(generator_version "10.0")
	(general
		(thickness 1.6)
		(legacy_teardrops no)
	)
	(paper "A4")
	(title_block
		(title "Bryce Canyon_SCC_16316-1_OCP.brd")
		(comment 1 "Bryce Canyon / footprints 1520-1527 of 1561")
	)
	(layers
		(0 "F.Cu" signal "TOP")
		(4 "In1.Cu" signal "L2GND")
		(6 "In2.Cu" signal "L3")
		(8 "In3.Cu" signal "L4VCC")
		(10 "In4.Cu" signal "L5VCC")
		(12 "In5.Cu" signal "L6")
		(14 "In6.Cu" signal "L7GND")
		(2 "B.Cu" signal "BOTTOM")
		(9 "F.Adhes" user "F.Adhesive")
		(11 "B.Adhes" user "B.Adhesive")
		(13 "F.Paste" user "Package Geometry/Pastemask Top")
		(15 "B.Paste" user "Package Geometry/Pastemask Bottom")
		(5 "F.SilkS" user "Ref Des/Silkscreen Top")
		(7 "B.SilkS" user "Ref Des/Silkscreen Bottom")
		(1 "F.Mask" user "Board Geometry/Soldermask Top")
		(3 "B.Mask" user "Board Geometry/Soldermask Bottom")
		(17 "Dwgs.User" user "User.Drawings")
		(19 "Cmts.User" user "User.Comments")
		(21 "Eco1.User" user "User.Eco1")
		(23 "Eco2.User" user "User.Eco2")
		(25 "Edge.Cuts" user "Board Geometry/Outline")
		(27 "Margin" user)
		(31 "F.CrtYd" user "Package Geometry/Place Bound Top")
		(29 "B.CrtYd" user "Package Geometry/Place Bound Bottom")
		(35 "F.Fab" user "Ref Des/Assembly Top")
		(33 "B.Fab" user "Ref Des/Assembly Bottom")
	)
	(footprint ""
		(layer "B.Cu")
		(at 126.5174 -78.49108 -90)
		(property "Reference" "C151"
			(at 0 0 90)
			(layer "B.SilkS")
			(hide yes)
			(effects
				(font
					(size 1.27 1.27)
				)
				(justify mirror)
			)
		)
		(property "Value" "SCD1U6D3V1KX-GP"
			(at 2.8321 -1.7399 270)
			(unlocked yes)
			(layer "B.Fab")
			(hide yes)
			(effects
				(font
					(size 1.016 1.016)
					(thickness 0.1524)
				)
				(justify mirror)
			)
		)
		(property "Device Type" "C0201H13"
			(at 2.8321 -3.2639 270)
			(unlocked yes)
			(layer "B.Fab")
			(hide yes)
			(effects
				(font
					(size 1.016 1.016)
					(thickness 0.1524)
				)
				(justify mirror)
			)
		)
		(duplicate_pad_numbers_are_jumpers no)
		(fp_rect
			(start 0.2794 0.6477)
			(end -0.2794 -0.6477)
			(stroke
				(width 0)
				(type default)
			)
			(fill no)
			(layer "B.CrtYd")
		)
		(fp_rect
			(start 0.2794 0.6477)
			(end -0.2794 -0.6477)
			(stroke
				(width 0)
				(type default)
			)
			(fill no)
			(layer "B.Fab")
		)
		(pad "1" smd custom
			(at 0 -0.2794 90)
			(size 0.0762 0.0762)
			(layers "B.Cu" "B.Mask" "B.Paste")
			(net "P1V8_E")
			(options
				(clearance outline)
				(anchor circle)
			)
			(primitives
				(gr_poly
					(pts
						(arc
							(start 0.1524 0.127)
							(mid 0.137521 0.162921)
							(end 0.1016 0.1778)
						)
						(arc
							(start -0.1016 0.1778)
							(mid -0.137521 0.162921)
							(end -0.1524 0.127)
						)
						(arc
							(start -0.1524 -0.127)
							(mid -0.137521 -0.162921)
							(end -0.1016 -0.1778)
						)
						(arc
							(start 0.1016 -0.1778)
							(mid 0.137521 -0.162921)
							(end 0.1524 -0.127)
						)
					)
					(width 0)
					(fill yes)
				)
			)
		)
		(pad "2" smd custom
			(at 0 0.2794 90)
			(size 0.0762 0.0762)
			(layers "B.Cu" "B.Mask" "B.Paste")
			(net "GND")
			(options
				(clearance outline)
				(anchor circle)
			)
			(primitives
				(gr_poly
					(pts
						(arc
							(start 0.1524 0.127)
							(mid 0.137521 0.162921)
							(end 0.1016 0.1778)
						)
						(arc
							(start -0.1016 0.1778)
							(mid -0.137521 0.162921)
							(end -0.1524 0.127)
						)
						(arc
							(start -0.1524 -0.127)
							(mid -0.137521 -0.162921)
							(end -0.1016 -0.1778)
						)
						(arc
							(start 0.1016 -0.1778)
							(mid 0.137521 -0.162921)
							(end 0.1524 -0.127)
						)
					)
					(width 0)
					(fill yes)
				)
			)
		)
	)
	(footprint ""
		(layer "B.Cu")
		(at 71.882 -73.152)
		(property "Reference" "R246"
			(at 0 0 0)
			(layer "B.SilkS")
			(hide yes)
			(effects
				(font
					(size 1.27 1.27)
				)
				(justify mirror)
			)
		)
		(property "Value" "10KR2F-2-GP"
			(at -0.064008 -3.993896 0)
			(unlocked yes)
			(layer "B.Fab")
			(hide yes)
			(effects
				(font
					(size 1.016 1.016)
					(thickness 0.1524)
				)
				(justify mirror)
			)
		)
		(property "Device Type" "R402H16"
			(at -0.064008 -5.517896 0)
			(unlocked yes)
			(layer "B.Fab")
			(hide yes)
			(effects
				(font
					(size 1.016 1.016)
					(thickness 0.1524)
				)
				(justify mirror)
			)
		)
		(duplicate_pad_numbers_are_jumpers no)
		(fp_line
			(start -0.508 -0.9398)
			(end 0.508 -0.9398)
			(stroke
				(width 0.1524)
				(type default)
			)
			(layer "B.SilkS")
		)
		(fp_line
			(start 0.508 -0.9398)
			(end 0.508 0.9398)
			(stroke
				(width 0.1524)
				(type default)
			)
			(layer "B.SilkS")
		)
		(fp_rect
			(start 0.508 0.9398)
			(end -0.508 -0.9398)
			(stroke
				(width 0)
				(type default)
			)
			(fill no)
			(layer "B.CrtYd")
		)
		(fp_rect
			(start 0.508 0.9398)
			(end -0.508 -0.9398)
			(stroke
				(width 0)
				(type default)
			)
			(fill no)
			(layer "B.Fab")
		)
		(pad "1" smd custom
			(at 0 -0.4445 180)
			(size 0.1397 0.1397)
			(layers "B.Cu" "B.Mask" "B.Paste")
			(net "P1V8_E")
			(options
				(clearance outline)
				(anchor circle)
			)
			(primitives
				(gr_poly
					(pts
						(arc
							(start -0.1778 0.2794)
							(mid -0.249642 0.249642)
							(end -0.2794 0.1778)
						)
						(arc
							(start -0.2794 -0.1778)
							(mid -0.249642 -0.249642)
							(end -0.1778 -0.2794)
						)
						(arc
							(start 0.1778 -0.2794)
							(mid 0.249642 -0.249642)
							(end 0.2794 -0.1778)
						)
						(arc
							(start 0.2794 0.1778)
							(mid 0.249642 0.249642)
							(end 0.1778 0.2794)
						)
					)
					(width 0)
					(fill yes)
				)
			)
		)
		(pad "2" smd custom
			(at 0 0.4445 180)
			(size 0.1397 0.1397)
			(layers "B.Cu" "B.Mask" "B.Paste")
			(net "EXP_BYTE_N")
			(options
				(clearance outline)
				(anchor circle)
			)
			(primitives
				(gr_poly
					(pts
						(arc
							(start -0.1778 0.2794)
							(mid -0.249642 0.249642)
							(end -0.2794 0.1778)
						)
						(arc
							(start -0.2794 -0.1778)
							(mid -0.249642 -0.249642)
							(end -0.1778 -0.2794)
						)
						(arc
							(start 0.1778 -0.2794)
							(mid 0.249642 -0.249642)
							(end 0.2794 -0.1778)
						)
						(arc
							(start 0.2794 0.1778)
							(mid 0.249642 0.249642)
							(end 0.1778 0.2794)
						)
					)
					(width 0)
					(fill yes)
				)
			)
		)
	)
	(footprint ""
		(layer "B.Cu")
		(at 96.497394 -50.366168 90)
		(property "Reference" "C88"
			(at 0 0 90)
			(layer "B.SilkS")
			(hide yes)
			(effects
				(font
					(size 1.27 1.27)
				)
				(justify mirror)
			)
		)
		(property "Value" "SCD01U16V1KX-GP"
			(at 2.8321 -1.7399 90)
			(unlocked yes)
			(layer "B.Fab")
			(hide yes)
			(effects
				(font
					(size 1.016 1.016)
					(thickness 0.1524)
				)
				(justify mirror)
			)
		)
		(property "Device Type" "C0201H13"
			(at 2.8321 -3.2639 90)
			(unlocked yes)
			(layer "B.Fab")
			(hide yes)
			(effects
				(font
					(size 1.016 1.016)
					(thickness 0.1524)
				)
				(justify mirror)
			)
		)
		(duplicate_pad_numbers_are_jumpers no)
		(fp_rect
			(start 0.2794 0.6477)
			(end -0.2794 -0.6477)
			(stroke
				(width 0)
				(type default)
			)
			(fill no)
			(layer "B.CrtYd")
		)
		(fp_rect
			(start 0.2794 0.6477)
			(end -0.2794 -0.6477)
			(stroke
				(width 0)
				(type default)
			)
			(fill no)
			(layer "B.Fab")
		)
		(pad "1" smd custom
			(at 0 -0.2794 270)
			(size 0.0762 0.0762)
			(layers "B.Cu" "B.Mask" "B.Paste")
			(net "PHY_DPB_TO_SCC_15_DP")
			(options
				(clearance outline)
				(anchor circle)
			)
			(primitives
				(gr_poly
					(pts
						(arc
							(start 0.1524 0.127)
							(mid 0.137521 0.162921)
							(end 0.1016 0.1778)
						)
						(arc
							(start -0.1016 0.1778)
							(mid -0.137521 0.162921)
							(end -0.1524 0.127)
						)
						(arc
							(start -0.1524 -0.127)
							(mid -0.137521 -0.162921)
							(end -0.1016 -0.1778)
						)
						(arc
							(start 0.1016 -0.1778)
							(mid 0.137521 -0.162921)
							(end 0.1524 -0.127)
						)
					)
					(width 0)
					(fill yes)
				)
			)
		)
		(pad "2" smd custom
			(at 0 0.2794 270)
			(size 0.0762 0.0762)
			(layers "B.Cu" "B.Mask" "B.Paste")
			(net "PHY_DPB_TO_SCC_C_15_DP")
			(options
				(clearance outline)
				(anchor circle)
			)
			(primitives
				(gr_poly
					(pts
						(arc
							(start 0.1524 0.127)
							(mid 0.137521 0.162921)
							(end 0.1016 0.1778)
						)
						(arc
							(start -0.1016 0.1778)
							(mid -0.137521 0.162921)
							(end -0.1524 0.127)
						)
						(arc
							(start -0.1524 -0.127)
							(mid -0.137521 -0.162921)
							(end -0.1016 -0.1778)
						)
						(arc
							(start 0.1016 -0.1778)
							(mid 0.137521 -0.162921)
							(end 0.1524 -0.127)
						)
					)
					(width 0)
					(fill yes)
				)
			)
		)
	)
	(footprint ""
		(layer "B.Cu")
		(at 130.82397 -44.379388 180)
		(property "Reference" "C30"
			(at 0 0 0)
			(layer "B.SilkS")
			(hide yes)
			(effects
				(font
					(size 1.27 1.27)
				)
				(justify mirror)
			)
		)
		(property "Value" "SCD01U16V1KX-GP"
			(at 2.8321 -1.7399 180)
			(unlocked yes)
			(layer "B.Fab")
			(hide yes)
			(effects
				(font
					(size 1.016 1.016)
					(thickness 0.1524)
				)
				(justify mirror)
			)
		)
		(property "Device Type" "C0201H13"
			(at 2.8321 -3.2639 180)
			(unlocked yes)
			(layer "B.Fab")
			(hide yes)
			(effects
				(font
					(size 1.016 1.016)
					(thickness 0.1524)
				)
				(justify mirror)
			)
		)
		(duplicate_pad_numbers_are_jumpers no)
		(fp_rect
			(start 0.2794 0.6477)
			(end -0.2794 -0.6477)
			(stroke
				(width 0)
				(type default)
			)
			(fill no)
			(layer "B.CrtYd")
		)
		(fp_rect
			(start 0.2794 0.6477)
			(end -0.2794 -0.6477)
			(stroke
				(width 0)
				(type default)
			)
			(fill no)
			(layer "B.Fab")
		)
		(pad "1" smd custom
			(at 0 -0.2794)
			(size 0.0762 0.0762)
			(layers "B.Cu" "B.Mask" "B.Paste")
			(net "PHY_DPB_TO_SCC_29_DN")
			(options
				(clearance outline)
				(anchor circle)
			)
			(primitives
				(gr_poly
					(pts
						(arc
							(start 0.1524 0.127)
							(mid 0.137521 0.162921)
							(end 0.1016 0.1778)
						)
						(arc
							(start -0.1016 0.1778)
							(mid -0.137521 0.162921)
							(end -0.1524 0.127)
						)
						(arc
							(start -0.1524 -0.127)
							(mid -0.137521 -0.162921)
							(end -0.1016 -0.1778)
						)
						(arc
							(start 0.1016 -0.1778)
							(mid 0.137521 -0.162921)
							(end 0.1524 -0.127)
						)
					)
					(width 0)
					(fill yes)
				)
			)
		)
		(pad "2" smd custom
			(at 0 0.2794)
			(size 0.0762 0.0762)
			(layers "B.Cu" "B.Mask" "B.Paste")
			(net "PHY_DPB_TO_SCC_C_29_DN")
			(options
				(clearance outline)
				(anchor circle)
			)
			(primitives
				(gr_poly
					(pts
						(arc
							(start 0.1524 0.127)
							(mid 0.137521 0.162921)
							(end 0.1016 0.1778)
						)
						(arc
							(start -0.1016 0.1778)
							(mid -0.137521 0.162921)
							(end -0.1524 0.127)
						)
						(arc
							(start -0.1524 -0.127)
							(mid -0.137521 -0.162921)
							(end -0.1016 -0.1778)
						)
						(arc
							(start 0.1016 -0.1778)
							(mid 0.137521 -0.162921)
							(end 0.1524 -0.127)
						)
					)
					(width 0)
					(fill yes)
				)
			)
		)
	)
	(footprint ""
		(layer "B.Cu")
		(at 166.847012 -40.914066)
		(property "Reference" "TP81"
			(at 0 0 0)
			(layer "B.SilkS")
			(hide yes)
			(effects
				(font
					(size 1.27 1.27)
				)
				(justify mirror)
			)
		)
		(property "Value" "TPAD28-2-GP"
			(at 0.0127 -1.6637 0)
			(unlocked yes)
			(layer "B.Fab")
			(hide yes)
			(effects
				(font
					(size 1.016 1.016)
					(thickness 0.1524)
				)
				(justify mirror)
			)
		)
		(property "Device Type" "TPAD28"
			(at 0.0127 -3.1877 0)
			(unlocked yes)
			(layer "B.Fab")
			(hide yes)
			(effects
				(font
					(size 1.016 1.016)
					(thickness 0.1524)
				)
				(justify mirror)
			)
		)
		(duplicate_pad_numbers_are_jumpers no)
		(fp_poly
			(pts
				(arc
					(start 0.3556 0)
					(mid -0.3556 0)
					(end 0.3556 0)
				)
			)
			(stroke
				(width 0)
				(type default)
			)
			(fill no)
			(layer "B.CrtYd")
		)
		(fp_poly
			(pts
				(arc
					(start 0.6096 0)
					(mid -0.6096 0)
					(end 0.6096 0)
				)
			)
			(stroke
				(width 0)
				(type default)
			)
			(fill no)
			(layer "B.Fab")
		)
		(pad "1" smd circle
			(at 0 0 180)
			(size 0.7112 0.7112)
			(layers "B.Cu" "B.Mask" "B.Paste")
			(net "SIO_DIN_0")
		)
	)
	(footprint ""
		(layer "B.Cu")
		(at 137.4648 -70.8914 -90)
		(property "Reference" "C14"
			(at 0 0 90)
			(layer "B.SilkS")
			(hide yes)
			(effects
				(font
					(size 1.27 1.27)
				)
				(justify mirror)
			)
		)
		(property "Value" "SCD01U16V1KX-GP"
			(at 2.8321 -1.7399 270)
			(unlocked yes)
			(layer "B.Fab")
			(hide yes)
			(effects
				(font
					(size 1.016 1.016)
					(thickness 0.1524)
				)
				(justify mirror)
			)
		)
		(property "Device Type" "C0201H13"
			(at 2.8321 -3.2639 270)
			(unlocked yes)
			(layer "B.Fab")
			(hide yes)
			(effects
				(font
					(size 1.016 1.016)
					(thickness 0.1524)
				)
				(justify mirror)
			)
		)
		(duplicate_pad_numbers_are_jumpers no)
		(fp_rect
			(start 0.2794 0.6477)
			(end -0.2794 -0.6477)
			(stroke
				(width 0)
				(type default)
			)
			(fill no)
			(layer "B.CrtYd")
		)
		(fp_rect
			(start 0.2794 0.6477)
			(end -0.2794 -0.6477)
			(stroke
				(width 0)
				(type default)
			)
			(fill no)
			(layer "B.Fab")
		)
		(pad "1" smd custom
			(at 0 -0.2794 90)
			(size 0.0762 0.0762)
			(layers "B.Cu" "B.Mask" "B.Paste")
			(net "PHY_DPB_TO_SCC_5_DN")
			(options
				(clearance outline)
				(anchor circle)
			)
			(primitives
				(gr_poly
					(pts
						(arc
							(start 0.1524 0.127)
							(mid 0.137521 0.162921)
							(end 0.1016 0.1778)
						)
						(arc
							(start -0.1016 0.1778)
							(mid -0.137521 0.162921)
							(end -0.1524 0.127)
						)
						(arc
							(start -0.1524 -0.127)
							(mid -0.137521 -0.162921)
							(end -0.1016 -0.1778)
						)
						(arc
							(start 0.1016 -0.1778)
							(mid 0.137521 -0.162921)
							(end 0.1524 -0.127)
						)
					)
					(width 0)
					(fill yes)
				)
			)
		)
		(pad "2" smd custom
			(at 0 0.2794 90)
			(size 0.0762 0.0762)
			(layers "B.Cu" "B.Mask" "B.Paste")
			(net "PHY_DPB_TO_SCC_C_5_DN")
			(options
				(clearance outline)
				(anchor circle)
			)
			(primitives
				(gr_poly
					(pts
						(arc
							(start 0.1524 0.127)
							(mid 0.137521 0.162921)
							(end 0.1016 0.1778)
						)
						(arc
							(start -0.1016 0.1778)
							(mid -0.137521 0.162921)
							(end -0.1524 0.127)
						)
						(arc
							(start -0.1524 -0.127)
							(mid -0.137521 -0.162921)
							(end -0.1016 -0.1778)
						)
						(arc
							(start 0.1016 -0.1778)
							(mid 0.137521 -0.162921)
							(end 0.1524 -0.127)
						)
					)
					(width 0)
					(fill yes)
				)
			)
		)
	)
	(footprint ""
		(layer "B.Cu")
		(at 138.4808 -89.6874)
		(property "Reference" "R53"
			(at 0 0 0)
			(layer "B.SilkS")
			(hide yes)
			(effects
				(font
					(size 1.27 1.27)
				)
				(justify mirror)
			)
		)
		(property "Value" "4K7R2F-GP"
			(at -0.064008 -3.993896 0)
			(unlocked yes)
			(layer "B.Fab")
			(hide yes)
			(effects
				(font
					(size 1.016 1.016)
					(thickness 0.1524)
				)
				(justify mirror)
			)
		)
		(property "Device Type" "R402H16"
			(at -0.064008 -5.517896 0)
			(unlocked yes)
			(layer "B.Fab")
			(hide yes)
			(effects
				(font
					(size 1.016 1.016)
					(thickness 0.1524)
				)
				(justify mirror)
			)
		)
		(duplicate_pad_numbers_are_jumpers no)
		(fp_line
			(start -0.508 -0.9398)
			(end 0.508 -0.9398)
			(stroke
				(width 0.1524)
				(type default)
			)
			(layer "B.SilkS")
		)
		(fp_line
			(start 0.508 -0.9398)
			(end 0.508 0.9398)
			(stroke
				(width 0.1524)
				(type default)
			)
			(layer "B.SilkS")
		)
		(fp_rect
			(start 0.508 0.9398)
			(end -0.508 -0.9398)
			(stroke
				(width 0)
				(type default)
			)
			(fill no)
			(layer "B.CrtYd")
		)
		(fp_rect
			(start 0.508 0.9398)
			(end -0.508 -0.9398)
			(stroke
				(width 0)
				(type default)
			)
			(fill no)
			(layer "B.Fab")
		)
		(pad "1" smd custom
			(at 0 -0.4445 180)
			(size 0.1397 0.1397)
			(layers "B.Cu" "B.Mask" "B.Paste")
			(net "P1V8_E")
			(options
				(clearance outline)
				(anchor circle)
			)
			(primitives
				(gr_poly
					(pts
						(arc
							(start -0.1778 0.2794)
							(mid -0.249642 0.249642)
							(end -0.2794 0.1778)
						)
						(arc
							(start -0.2794 -0.1778)
							(mid -0.249642 -0.249642)
							(end -0.1778 -0.2794)
						)
						(arc
							(start 0.1778 -0.2794)
							(mid 0.249642 -0.249642)
							(end 0.2794 -0.1778)
						)
						(arc
							(start 0.2794 0.1778)
							(mid 0.249642 0.249642)
							(end 0.1778 0.2794)
						)
					)
					(width 0)
					(fill yes)
				)
			)
		)
		(pad "2" smd custom
			(at 0 0.4445 180)
			(size 0.1397 0.1397)
			(layers "B.Cu" "B.Mask" "B.Paste")
			(net "I2C_SCC_SDA2_LS")
			(options
				(clearance outline)
				(anchor circle)
			)
			(primitives
				(gr_poly
					(pts
						(arc
							(start -0.1778 0.2794)
							(mid -0.249642 0.249642)
							(end -0.2794 0.1778)
						)
						(arc
							(start -0.2794 -0.1778)
							(mid -0.249642 -0.249642)
							(end -0.1778 -0.2794)
						)
						(arc
							(start 0.1778 -0.2794)
							(mid 0.249642 -0.249642)
							(end 0.2794 -0.1778)
						)
						(arc
							(start 0.2794 0.1778)
							(mid 0.249642 0.249642)
							(end 0.1778 0.2794)
						)
					)
					(width 0)
					(fill yes)
				)
			)
		)
	)
	(footprint ""
		(layer "B.Cu")
		(at 125.998986 -51.995578)
		(property "Reference" "C289"
			(at 0 0 0)
			(layer "B.SilkS")
			(hide yes)
			(effects
				(font
					(size 1.27 1.27)
				)
				(justify mirror)
			)
		)
		(property "Value" "SCD1U6D3V1KX-GP"
			(at 2.8321 -1.7399 0)
			(unlocked yes)
			(layer "B.Fab")
			(hide yes)
			(effects
				(font
					(size 1.016 1.016)
					(thickness 0.1524)
				)
				(justify mirror)
			)
		)
		(property "Device Type" "C0201H13"
			(at 2.8321 -3.2639 0)
			(unlocked yes)
			(layer "B.Fab")
			(hide yes)
			(effects
				(font
					(size 1.016 1.016)
					(thickness 0.1524)
				)
				(justify mirror)
			)
		)
		(duplicate_pad_numbers_are_jumpers no)
		(fp_rect
			(start 0.2794 0.6477)
			(end -0.2794 -0.6477)
			(stroke
				(width 0)
				(type default)
			)
			(fill no)
			(layer "B.CrtYd")
		)
		(fp_rect
			(start 0.2794 0.6477)
			(end -0.2794 -0.6477)
			(stroke
				(width 0)
				(type default)
			)
			(fill no)
			(layer "B.Fab")
		)
		(pad "1" smd custom
			(at 0 -0.2794 180)
			(size 0.0762 0.0762)
			(layers "B.Cu" "B.Mask" "B.Paste")
			(net "GB_VDDA")
			(options
				(clearance outline)
				(anchor circle)
			)
			(primitives
				(gr_poly
					(pts
						(arc
							(start 0.1524 0.127)
							(mid 0.137521 0.162921)
							(end 0.1016 0.1778)
						)
						(arc
							(start -0.1016 0.1778)
							(mid -0.137521 0.162921)
							(end -0.1524 0.127)
						)
						(arc
							(start -0.1524 -0.127)
							(mid -0.137521 -0.162921)
							(end -0.1016 -0.1778)
						)
						(arc
							(start 0.1016 -0.1778)
							(mid 0.137521 -0.162921)
							(end 0.1524 -0.127)
						)
					)
					(width 0)
					(fill yes)
				)
			)
		)
		(pad "2" smd custom
			(at 0 0.2794 180)
			(size 0.0762 0.0762)
			(layers "B.Cu" "B.Mask" "B.Paste")
			(net "GND")
			(options
				(clearance outline)
				(anchor circle)
			)
			(primitives
				(gr_poly
					(pts
						(arc
							(start 0.1524 0.127)
							(mid 0.137521 0.162921)
							(end 0.1016 0.1778)
						)
						(arc
							(start -0.1016 0.1778)
							(mid -0.137521 0.162921)
							(end -0.1524 0.127)
						)
						(arc
							(start -0.1524 -0.127)
							(mid -0.137521 -0.162921)
							(end -0.1016 -0.1778)
						)
						(arc
							(start 0.1016 -0.1778)
							(mid 0.137521 -0.162921)
							(end 0.1524 -0.127)
						)
					)
					(width 0)
					(fill yes)
				)
			)
		)
	)
)
